# T6G (Grand Teton) — schematic netlist excerpt (pin names and nets, part order shuffled) for the footprints in the layout excerpt that follows; sources: Cadence DE-HDL packaged netlist, KiCad conversion of 04192023_DAF0TMB3IC0_F0TG_MB_C_brd_V02_OCP.brd

R1680  Q_RES  10 1% CHIP  pkg 0402LF  page 92 : A = I3C_SPD_DDRGL_CPU0_SDA ; B = I3C_SPD_DDRG_CPU0_SDA
C349  Q_CAP  0.1UF 10V 10% X7S  pkg C0201  page 334 : A = P0V9_CPU1_RT1_2A ; B = GND
C490  Q_CAP  10UF 6.3V 20% X6S  pkg C0402  page 356 : A = P0V9_CPU1_RT3_2A ; B = GND

(kicad_pcb
	(version 20260206)
	(generator "pcbnew")
	(generator_version "10.0")
	(general
		(thickness 1.6)
		(legacy_teardrops no)
	)
	(paper "A4")
	(title_block
		(title "04192023_DAF0TMB3IC0_F0TG_MB_C_brd_V02_OCP.brd")
		(comment 1 "Grand Teton / footprints 8102-8104 of 8354")
	)
	(layers
		(0 "F.Cu" signal "TOP")
		(4 "In1.Cu" signal "GND")
		(6 "In2.Cu" signal "IN1")
		(8 "In3.Cu" signal "GND1")
		(10 "In4.Cu" signal "IN2")
		(12 "In5.Cu" signal "GND2")
		(14 "In6.Cu" signal "IN3")
		(16 "In7.Cu" signal "GND3")
		(18 "In8.Cu" signal "VCC")
		(20 "In9.Cu" signal "VCC1")
		(22 "In10.Cu" signal "GND4")
		(24 "In11.Cu" signal "IN4")
		(26 "In12.Cu" signal "GND5")
		(28 "In13.Cu" signal "IN5")
		(30 "In14.Cu" signal "GND6")
		(32 "In15.Cu" signal "IN6")
		(34 "In16.Cu" signal "GND7")
		(2 "B.Cu" signal "BOTTOM")
		(9 "F.Adhes" user "F.Adhesive")
		(11 "B.Adhes" user "B.Adhesive")
		(13 "F.Paste" user "Package Geometry/Pastemask Top")
		(15 "B.Paste" user "Package Geometry/Pastemask Bottom")
		(5 "F.SilkS" user "Ref Des/Silkscreen Top")
		(7 "B.SilkS" user "Ref Des/Silkscreen Bottom")
		(1 "F.Mask" user "Board Geometry/Soldermask Top")
		(3 "B.Mask" user "Board Geometry/Soldermask Bottom")
		(17 "Dwgs.User" user "User.Drawings")
		(19 "Cmts.User" user "User.Comments")
		(21 "Eco1.User" user "User.Eco1")
		(23 "Eco2.User" user "User.Eco2")
		(25 "Edge.Cuts" user "Board Geometry/Outline")
		(27 "Margin" user)
		(31 "F.CrtYd" user "Package Geometry/Place Bound Top")
		(29 "B.CrtYd" user "Package Geometry/Place Bound Bottom")
		(35 "F.Fab" user "Ref Des/Assembly Top")
		(33 "B.Fab" user "Ref Des/Assembly Bottom")
	)
	(footprint ""
		(layer "B.Cu")
		(at 99.94519 -387.768592 180)
		(property "Reference" "C349"
			(at 0 0 0)
			(layer "B.SilkS")
			(hide yes)
			(effects
				(font
					(size 1.27 1.27)
				)
				(justify mirror)
			)
		)
		(property "Value" ""
			(at 0 0 0)
			(layer "B.Fab")
			(effects
				(font
					(size 1.27 1.27)
				)
				(justify mirror)
			)
		)
		(duplicate_pad_numbers_are_jumpers no)
		(fp_line
			(start 0.299974 0.150114)
			(end 0.299974 -0.150114)
			(stroke
				(width 0.1)
				(type default)
			)
			(layer "B.Fab")
		)
		(fp_line
			(start 0.299974 -0.150114)
			(end -0.299974 -0.150114)
			(stroke
				(width 0.1)
				(type default)
			)
			(layer "B.Fab")
		)
		(fp_line
			(start -0.299974 0.150114)
			(end 0.299974 0.150114)
			(stroke
				(width 0.1)
				(type default)
			)
			(layer "B.Fab")
		)
		(fp_line
			(start -0.299974 -0.150114)
			(end -0.299974 0.150114)
			(stroke
				(width 0.1)
				(type default)
			)
			(layer "B.Fab")
		)
		(pad "1" smd rect
			(at 0.2667 0)
			(size 0.3048 0.381)
			(layers "B.Cu" "B.Mask" "B.Paste")
			(net "P0V9_CPU1_RT1_2A")
		)
		(pad "2" smd rect
			(at -0.2667 0)
			(size 0.3048 0.381)
			(layers "B.Cu" "B.Mask" "B.Paste")
			(net "GND")
		)
	)
	(footprint ""
		(layer "B.Cu")
		(at 415.712402 -195.85051 180)
		(property "Reference" "R1680"
			(at 0 0 0)
			(layer "B.SilkS")
			(hide yes)
			(effects
				(font
					(size 1.27 1.27)
				)
				(justify mirror)
			)
		)
		(property "Value" ""
			(at 0 0 0)
			(layer "B.Fab")
			(effects
				(font
					(size 1.27 1.27)
				)
				(justify mirror)
			)
		)
		(duplicate_pad_numbers_are_jumpers no)
		(fp_line
			(start 0.7874 0.4064)
			(end 0.7874 -0.4064)
			(stroke
				(width 0.1524)
				(type default)
			)
			(layer "B.SilkS")
		)
		(fp_line
			(start 0.7874 -0.4064)
			(end -0.7874 -0.4064)
			(stroke
				(width 0.1524)
				(type default)
			)
			(layer "B.SilkS")
		)
		(fp_line
			(start -0.7874 0.4064)
			(end 0.7874 0.4064)
			(stroke
				(width 0.1524)
				(type default)
			)
			(layer "B.SilkS")
		)
		(fp_line
			(start -0.7874 -0.4064)
			(end -0.7874 0.4064)
			(stroke
				(width 0.1524)
				(type default)
			)
			(layer "B.SilkS")
		)
		(fp_line
			(start 0.67945 0.3048)
			(end 0.67945 -0.305054)
			(stroke
				(width 0.1)
				(type default)
			)
			(layer "B.Fab")
		)
		(fp_line
			(start 0.67945 -0.305054)
			(end 0.12065 -0.305054)
			(stroke
				(width 0.1)
				(type default)
			)
			(layer "B.Fab")
		)
		(fp_line
			(start 0.12065 0.3048)
			(end 0.67945 0.3048)
			(stroke
				(width 0.1)
				(type default)
			)
			(layer "B.Fab")
		)
		(fp_line
			(start 0.12065 0.2794)
			(end 0.12065 0.3048)
			(stroke
				(width 0.1)
				(type default)
			)
			(layer "B.Fab")
		)
		(fp_line
			(start 0.12065 -0.2794)
			(end -0.12065 -0.2794)
			(stroke
				(width 0.1)
				(type default)
			)
			(layer "B.Fab")
		)
		(fp_line
			(start 0.12065 -0.305054)
			(end 0.12065 -0.2794)
			(stroke
				(width 0.1)
				(type default)
			)
			(layer "B.Fab")
		)
		(fp_line
			(start -0.120396 0.3048)
			(end -0.120396 0.2794)
			(stroke
				(width 0.1)
				(type default)
			)
			(layer "B.Fab")
		)
		(fp_line
			(start -0.120396 0.2794)
			(end 0.12065 0.2794)
			(stroke
				(width 0.1)
				(type default)
			)
			(layer "B.Fab")
		)
		(fp_line
			(start -0.12065 -0.2794)
			(end -0.12065 -0.3048)
			(stroke
				(width 0.1)
				(type default)
			)
			(layer "B.Fab")
		)
		(fp_line
			(start -0.12065 -0.3048)
			(end -0.67945 -0.3048)
			(stroke
				(width 0.1)
				(type default)
			)
			(layer "B.Fab")
		)
		(fp_line
			(start -0.67945 0.3048)
			(end -0.120396 0.3048)
			(stroke
				(width 0.1)
				(type default)
			)
			(layer "B.Fab")
		)
		(fp_line
			(start -0.67945 -0.3048)
			(end -0.67945 0.3048)
			(stroke
				(width 0.1)
				(type default)
			)
			(layer "B.Fab")
		)
		(pad "1" smd circle
			(at 0.40005 0)
			(size 0 0)
			(layers "B.Cu" "B.Mask" "B.Paste")
			(net "I3C_SPD_DDRGL_CPU0_SDA")
		)
		(pad "2" smd circle
			(at -0.40005 0)
			(size 0 0)
			(layers "B.Cu" "B.Mask" "B.Paste")
			(net "I3C_SPD_DDRG_CPU0_SDA")
		)
	)
	(footprint ""
		(layer "B.Cu")
		(at 118.091204 -390.560052 90)
		(property "Reference" "C490"
			(at 0 0 90)
			(layer "B.SilkS")
			(hide yes)
			(effects
				(font
					(size 1.27 1.27)
				)
				(justify mirror)
			)
		)
		(property "Value" ""
			(at 0 0 90)
			(layer "B.Fab")
			(effects
				(font
					(size 1.27 1.27)
				)
				(justify mirror)
			)
		)
		(duplicate_pad_numbers_are_jumpers no)
		(fp_line
			(start 0.7874 -0.4064)
			(end -0.7874 -0.4064)
			(stroke
				(width 0.1524)
				(type default)
			)
			(layer "B.SilkS")
		)
		(fp_line
			(start -0.7874 -0.4064)
			(end -0.7874 0.4064)
			(stroke
				(width 0.1524)
				(type default)
			)
			(layer "B.SilkS")
		)
		(fp_line
			(start 0.7874 0.4064)
			(end 0.7874 -0.4064)
			(stroke
				(width 0.1524)
				(type default)
			)
			(layer "B.SilkS")
		)
		(fp_line
			(start -0.7874 0.4064)
			(end 0.7874 0.4064)
			(stroke
				(width 0.1524)
				(type default)
			)
			(layer "B.SilkS")
		)
		(fp_line
			(start 0.67945 -0.305054)
			(end 0.12065 -0.305054)
			(stroke
				(width 0.1)
				(type default)
			)
			(layer "B.Fab")
		)
		(fp_line
			(start 0.12065 -0.305054)
			(end 0.12065 -0.2794)
			(stroke
				(width 0.1)
				(type default)
			)
			(layer "B.Fab")
		)
		(fp_line
			(start -0.12065 -0.3048)
			(end -0.67945 -0.3048)
			(stroke
				(width 0.1)
				(type default)
			)
			(layer "B.Fab")
		)
		(fp_line
			(start -0.67945 -0.3048)
			(end -0.67945 0.3048)
			(stroke
				(width 0.1)
				(type default)
			)
			(layer "B.Fab")
		)
		(fp_line
			(start 0.12065 -0.2794)
			(end -0.12065 -0.2794)
			(stroke
				(width 0.1)
				(type default)
			)
			(layer "B.Fab")
		)
		(fp_line
			(start -0.12065 -0.2794)
			(end -0.12065 -0.3048)
			(stroke
				(width 0.1)
				(type default)
			)
			(layer "B.Fab")
		)
		(fp_line
			(start 0.12065 0.2794)
			(end 0.12065 0.3048)
			(stroke
				(width 0.1)
				(type default)
			)
			(layer "B.Fab")
		)
		(fp_line
			(start -0.120396 0.2794)
			(end 0.12065 0.2794)
			(stroke
				(width 0.1)
				(type default)
			)
			(layer "B.Fab")
		)
		(fp_line
			(start 0.67945 0.3048)
			(end 0.67945 -0.305054)
			(stroke
				(width 0.1)
				(type default)
			)
			(layer "B.Fab")
		)
		(fp_line
			(start 0.12065 0.3048)
			(end 0.67945 0.3048)
			(stroke
				(width 0.1)
				(type default)
			)
			(layer "B.Fab")
		)
		(fp_line
			(start -0.120396 0.3048)
			(end -0.120396 0.2794)
			(stroke
				(width 0.1)
				(type default)
			)
			(layer "B.Fab")
		)
		(fp_line
			(start -0.67945 0.3048)
			(end -0.120396 0.3048)
			(stroke
				(width 0.1)
				(type default)
			)
			(layer "B.Fab")
		)
		(pad "1" smd circle
			(at 0.40005 0 270)
			(size 0 0)
			(layers "B.Cu" "B.Mask" "B.Paste")
			(net "P0V9_CPU1_RT3_2A")
		)
		(pad "2" smd circle
			(at -0.40005 0 270)
			(size 0 0)
			(layers "B.Cu" "B.Mask" "B.Paste")
			(net "GND")
		)
	)
)
